(kicad_pcb
	(version 20260206)
	(generator "pcbnew")
	(generator_version "10.0")
	(general
		(thickness 1.6)
		(legacy_teardrops no)
	)
	(paper "A4")
	(title_block
		(title "Bryce Canyon_F.DPB_16315-1-OCP.brd")
		(comment 1 "Bryce Canyon / footprints 697-705 of 2223")
	)
	(layers
		(0 "F.Cu" signal "TOP")
		(4 "In1.Cu" signal "L2GND")
		(6 "In2.Cu" signal "L3")
		(8 "In3.Cu" signal "L4GND")
		(10 "In4.Cu" signal "L5")
		(12 "In5.Cu" signal "L6VCC")
		(14 "In6.Cu" signal "L7VCC")
		(16 "In7.Cu" signal "L8")
		(18 "In8.Cu" signal "L9GND")
		(20 "In9.Cu" signal "L10")
		(22 "In10.Cu" signal "L11GND")
		(2 "B.Cu" signal "BOTTOM")
		(9 "F.Adhes" user "F.Adhesive")
		(11 "B.Adhes" user "B.Adhesive")
		(13 "F.Paste" user "Package Geometry/Pastemask Top")
		(15 "B.Paste" user "Package Geometry/Pastemask Bottom")
		(5 "F.SilkS" user "Ref Des/Silkscreen Top")
		(7 "B.SilkS" user "Ref Des/Silkscreen Bottom")
		(1 "F.Mask" user "Board Geometry/Soldermask Top")
		(3 "B.Mask" user "Board Geometry/Soldermask Bottom")
		(17 "Dwgs.User" user "User.Drawings")
		(19 "Cmts.User" user "User.Comments")
		(21 "Eco1.User" user "User.Eco1")
		(23 "Eco2.User" user "User.Eco2")
		(25 "Edge.Cuts" user "Board Geometry/Outline")
		(27 "Margin" user)
		(31 "F.CrtYd" user "Package Geometry/Place Bound Top")
		(29 "B.CrtYd" user "Package Geometry/Place Bound Bottom")
		(35 "F.Fab" user "Ref Des/Assembly Top")
		(33 "B.Fab" user "Ref Des/Assembly Bottom")
	)
	(footprint ""
		(layer "F.Cu")
		(at 118.585996 -186.287918)
		(property "Reference" "C241"
			(at 0 0 0)
			(layer "F.SilkS")
			(hide yes)
			(effects
				(font
					(size 1.27 1.27)
				)
			)
		)
		(property "Value" "SC4D7U25V5KX-1-GP"
			(at -0.0762 -6.1214 0)
			(unlocked yes)
			(layer "F.Fab")
			(hide yes)
			(effects
				(font
					(size 1.016 1.016)
					(thickness 0.1524)
				)
			)
		)
		(property "Device Type" "C805H58"
			(at -0.0762 -8.1534 0)
			(unlocked yes)
			(layer "F.Fab")
			(hide yes)
			(effects
				(font
					(size 1.016 1.016)
					(thickness 0.1524)
				)
			)
		)
		(duplicate_pad_numbers_are_jumpers no)
		(fp_line
			(start 0.635 0)
			(end -0.635 0)
			(stroke
				(width 0.508)
				(type default)
			)
			(layer "F.SilkS")
		)
		(fp_rect
			(start -0.9652 1.778)
			(end 0.9652 -1.778)
			(stroke
				(width 0)
				(type default)
			)
			(fill no)
			(layer "F.CrtYd")
		)
		(fp_poly
			(pts
				(xy -0.9652 -1.778) (xy 0.9652 -1.778) (xy 0.9652 1.778) (xy -0.9652 1.778)
			)
			(stroke
				(width 0)
				(type default)
			)
			(fill no)
			(layer "F.Fab")
		)
		(pad "1" smd rect
			(at 0 -0.9652)
			(size 1.397 1.143)
			(layers "F.Cu" "F.Mask" "F.Paste")
			(net "P12V_HDD15")
		)
		(pad "2" smd rect
			(at 0 0.9652)
			(size 1.397 1.143)
			(layers "F.Cu" "F.Mask" "F.Paste")
			(net "GND")
		)
	)
	(footprint ""
		(layer "F.Cu")
		(at 479.384614 -43.660568 -90)
		(property "Reference" "C494"
			(at 0 0 270)
			(layer "F.SilkS")
			(hide yes)
			(effects
				(font
					(size 1.27 1.27)
				)
			)
		)
		(property "Value" "SCD01U16V1KX-GP"
			(at -2.8321 -1.7399 270)
			(unlocked yes)
			(layer "F.Fab")
			(hide yes)
			(effects
				(font
					(size 1.016 1.016)
					(thickness 0.1524)
				)
			)
		)
		(property "Device Type" "C0201H13"
			(at -2.8321 -3.2639 270)
			(unlocked yes)
			(layer "F.Fab")
			(hide yes)
			(effects
				(font
					(size 1.016 1.016)
					(thickness 0.1524)
				)
			)
		)
		(duplicate_pad_numbers_are_jumpers no)
		(fp_rect
			(start -0.2794 0.6477)
			(end 0.2794 -0.6477)
			(stroke
				(width 0)
				(type default)
			)
			(fill no)
			(layer "F.CrtYd")
		)
		(fp_rect
			(start -0.2794 0.6477)
			(end 0.2794 -0.6477)
			(stroke
				(width 0)
				(type default)
			)
			(fill no)
			(layer "F.Fab")
		)
		(pad "1" smd custom
			(at 0 -0.2794 270)
			(size 0.0762 0.0762)
			(layers "F.Cu" "F.Mask" "F.Paste")
			(net "SAS_HDD_RX_P35")
			(options
				(clearance outline)
				(anchor circle)
			)
			(primitives
				(gr_poly
					(pts
						(arc
							(start 0.1524 -0.127)
							(mid 0.137521 -0.162921)
							(end 0.1016 -0.1778)
						)
						(arc
							(start -0.1016 -0.1778)
							(mid -0.137521 -0.162921)
							(end -0.1524 -0.127)
						)
						(arc
							(start -0.1524 0.127)
							(mid -0.137521 0.162921)
							(end -0.1016 0.1778)
						)
						(arc
							(start 0.1016 0.1778)
							(mid 0.137521 0.162921)
							(end 0.1524 0.127)
						)
					)
					(width 0)
					(fill yes)
				)
			)
		)
		(pad "2" smd custom
			(at 0 0.2794 270)
			(size 0.0762 0.0762)
			(layers "F.Cu" "F.Mask" "F.Paste")
			(net "PHY_SCC_A_TO_DRV_A_35_DP")
			(options
				(clearance outline)
				(anchor circle)
			)
			(primitives
				(gr_poly
					(pts
						(arc
							(start 0.1524 -0.127)
							(mid 0.137521 -0.162921)
							(end 0.1016 -0.1778)
						)
						(arc
							(start -0.1016 -0.1778)
							(mid -0.137521 -0.162921)
							(end -0.1524 -0.127)
						)
						(arc
							(start -0.1524 0.127)
							(mid -0.137521 0.162921)
							(end -0.1016 0.1778)
						)
						(arc
							(start 0.1016 0.1778)
							(mid 0.137521 0.162921)
							(end 0.1524 0.127)
						)
					)
					(width 0)
					(fill yes)
				)
			)
		)
	)
	(footprint ""
		(layer "F.Cu")
		(at 87.340948 -304.462942 180)
		(property "Reference" "C73"
			(at 0 0 180)
			(layer "F.SilkS")
			(hide yes)
			(effects
				(font
					(size 1.27 1.27)
				)
			)
		)
		(property "Value" "SC1U25V3KX-GP"
			(at 0 -2.8194 180)
			(unlocked yes)
			(layer "F.Fab")
			(hide yes)
			(effects
				(font
					(size 1.016 1.016)
					(thickness 0.1524)
				)
			)
		)
		(property "Device Type" "C603H36"
			(at 0 -4.3434 180)
			(unlocked yes)
			(layer "F.Fab")
			(hide yes)
			(effects
				(font
					(size 1.016 1.016)
					(thickness 0.1524)
				)
			)
		)
		(duplicate_pad_numbers_are_jumpers no)
		(fp_line
			(start 0.508 0)
			(end -0.508 0)
			(stroke
				(width 0.2032)
				(type default)
			)
			(layer "F.SilkS")
		)
		(fp_rect
			(start -0.5842 1.3335)
			(end 0.5842 -1.3335)
			(stroke
				(width 0)
				(type default)
			)
			(fill no)
			(layer "F.CrtYd")
		)
		(fp_rect
			(start -0.5842 1.3335)
			(end 0.5842 -1.3335)
			(stroke
				(width 0)
				(type default)
			)
			(fill no)
			(layer "F.Fab")
		)
		(pad "1" smd custom
			(at 0 -0.762 180)
			(size 0.2159 0.2159)
			(layers "F.Cu" "F.Mask" "F.Paste")
			(net "P12V_HDD2")
			(options
				(clearance outline)
				(anchor circle)
			)
			(primitives
				(gr_poly
					(pts
						(arc
							(start -0.3302 -0.4318)
							(mid -0.402042 -0.402042)
							(end -0.4318 -0.3302)
						)
						(arc
							(start -0.4318 0.3302)
							(mid -0.402042 0.402042)
							(end -0.3302 0.4318)
						)
						(arc
							(start 0.3302 0.4318)
							(mid 0.402042 0.402042)
							(end 0.4318 0.3302)
						)
						(arc
							(start 0.4318 -0.3302)
							(mid 0.402042 -0.402042)
							(end 0.3302 -0.4318)
						)
					)
					(width 0)
					(fill yes)
				)
			)
		)
		(pad "2" smd custom
			(at 0 0.762 180)
			(size 0.2159 0.2159)
			(layers "F.Cu" "F.Mask" "F.Paste")
			(net "GND")
			(options
				(clearance outline)
				(anchor circle)
			)
			(primitives
				(gr_poly
					(pts
						(arc
							(start -0.3302 -0.4318)
							(mid -0.402042 -0.402042)
							(end -0.4318 -0.3302)
						)
						(arc
							(start -0.4318 0.3302)
							(mid -0.402042 0.402042)
							(end -0.3302 0.4318)
						)
						(arc
							(start 0.3302 0.4318)
							(mid 0.402042 0.402042)
							(end 0.4318 0.3302)
						)
						(arc
							(start 0.4318 -0.3302)
							(mid 0.402042 -0.402042)
							(end 0.3302 -0.4318)
						)
					)
					(width 0)
					(fill yes)
				)
			)
		)
	)
	(footprint ""
		(layer "F.Cu")
		(at 51.599846 -291.000942 -90)
		(property "Reference" "C54"
			(at 0 0 270)
			(layer "F.SilkS")
			(hide yes)
			(effects
				(font
					(size 1.27 1.27)
				)
			)
		)
		(property "Value" "SC10U16V6KX-2GP"
			(at -0.0762 -5.1308 270)
			(unlocked yes)
			(layer "F.Fab")
			(hide yes)
			(effects
				(font
					(size 1.016 1.016)
					(thickness 0.1524)
				)
			)
		)
		(property "Device Type" "C1206H71"
			(at -0.127 -6.6548 270)
			(unlocked yes)
			(layer "F.Fab")
			(hide yes)
			(effects
				(font
					(size 1.016 1.016)
					(thickness 0.1524)
				)
			)
		)
		(duplicate_pad_numbers_are_jumpers no)
		(fp_line
			(start -1.016 2.2352)
			(end -1.016 0.8382)
			(stroke
				(width 0.1524)
				(type default)
			)
			(layer "F.SilkS")
		)
		(fp_line
			(start 1.016 2.2352)
			(end -1.016 2.2352)
			(stroke
				(width 0.1524)
				(type default)
			)
			(layer "F.SilkS")
		)
		(fp_line
			(start 1.016 0.8382)
			(end 1.016 2.2352)
			(stroke
				(width 0.1524)
				(type default)
			)
			(layer "F.SilkS")
		)
		(fp_line
			(start -1.016 -0.8382)
			(end -1.016 -2.2352)
			(stroke
				(width 0.1524)
				(type default)
			)
			(layer "F.SilkS")
		)
		(fp_line
			(start -1.016 -2.2352)
			(end 1.016 -2.2352)
			(stroke
				(width 0.1524)
				(type default)
			)
			(layer "F.SilkS")
		)
		(fp_line
			(start 1.016 -2.2352)
			(end 1.016 -0.8382)
			(stroke
				(width 0.1524)
				(type default)
			)
			(layer "F.SilkS")
		)
		(fp_rect
			(start -1.0922 2.3114)
			(end 1.0922 -2.3114)
			(stroke
				(width 0)
				(type default)
			)
			(fill no)
			(layer "F.CrtYd")
		)
		(fp_poly
			(pts
				(xy 1.0922 -2.3114) (xy 1.0922 2.3114) (xy -1.0922 2.3114) (xy -1.0922 -2.3114)
			)
			(stroke
				(width 0)
				(type default)
			)
			(fill no)
			(layer "F.Fab")
		)
		(pad "1" smd rect
			(at 0 -1.397 270)
			(size 1.651 1.27)
			(layers "F.Cu" "F.Mask" "F.Paste")
			(net "P5V_HDD1")
		)
		(pad "2" smd rect
			(at 0 1.397 270)
			(size 1.651 1.27)
			(layers "F.Cu" "F.Mask" "F.Paste")
			(net "GND")
		)
	)
	(footprint ""
		(layer "F.Cu")
		(at 143.3449 -242.25377)
		(property "Reference" "R222"
			(at 0 0 0)
			(layer "F.SilkS")
			(hide yes)
			(effects
				(font
					(size 1.27 1.27)
				)
			)
		)
		(property "Value" "130R3F-GP"
			(at -0.0254 -2.5146 0)
			(unlocked yes)
			(layer "F.Fab")
			(hide yes)
			(effects
				(font
					(size 1.016 1.016)
					(thickness 0.1524)
				)
			)
		)
		(property "Device Type" "R603H22"
			(at -0.0254 -4.0386 0)
			(unlocked yes)
			(layer "F.Fab")
			(hide yes)
			(effects
				(font
					(size 1.016 1.016)
					(thickness 0.1524)
				)
			)
		)
		(duplicate_pad_numbers_are_jumpers no)
		(fp_line
			(start -0.4826 0)
			(end -0.2032 0)
			(stroke
				(width 0.2032)
				(type default)
			)
			(layer "F.SilkS")
		)
		(fp_line
			(start 0.2032 0)
			(end 0.4826 0)
			(stroke
				(width 0.2032)
				(type default)
			)
			(layer "F.SilkS")
		)
		(fp_rect
			(start -0.5842 1.3335)
			(end 0.5842 -1.3335)
			(stroke
				(width 0)
				(type default)
			)
			(fill no)
			(layer "F.CrtYd")
		)
		(fp_rect
			(start -0.5842 1.3335)
			(end 0.5842 -1.3335)
			(stroke
				(width 0)
				(type default)
			)
			(fill no)
			(layer "F.Fab")
		)
		(pad "1" smd custom
			(at 0 -0.762)
			(size 0.2159 0.2159)
			(layers "F.Cu" "F.Mask" "F.Paste")
			(net "P5V_A_1")
			(options
				(clearance outline)
				(anchor circle)
			)
			(primitives
				(gr_poly
					(pts
						(arc
							(start -0.3302 -0.4318)
							(mid -0.402042 -0.402042)
							(end -0.4318 -0.3302)
						)
						(arc
							(start -0.4318 0.3302)
							(mid -0.402042 0.402042)
							(end -0.3302 0.4318)
						)
						(arc
							(start 0.3302 0.4318)
							(mid 0.402042 0.402042)
							(end 0.4318 0.3302)
						)
						(arc
							(start 0.4318 -0.3302)
							(mid 0.402042 -0.402042)
							(end 0.3302 -0.4318)
						)
					)
					(width 0)
					(fill yes)
				)
			)
		)
		(pad "2" smd custom
			(at 0 0.762)
			(size 0.2159 0.2159)
			(layers "F.Cu" "F.Mask" "F.Paste")
			(net "FLT_HDD4")
			(options
				(clearance outline)
				(anchor circle)
			)
			(primitives
				(gr_poly
					(pts
						(arc
							(start -0.3302 -0.4318)
							(mid -0.402042 -0.402042)
							(end -0.4318 -0.3302)
						)
						(arc
							(start -0.4318 0.3302)
							(mid -0.402042 0.402042)
							(end -0.3302 0.4318)
						)
						(arc
							(start 0.3302 0.4318)
							(mid 0.402042 0.402042)
							(end 0.4318 0.3302)
						)
						(arc
							(start 0.4318 -0.3302)
							(mid 0.402042 -0.402042)
							(end 0.3302 -0.4318)
						)
					)
					(width 0)
					(fill yes)
				)
			)
		)
	)
	(footprint ""
		(layer "F.Cu")
		(at 130.447796 -176.127918 90)
		(property "Reference" "C237"
			(at 0 0 90)
			(layer "F.SilkS")
			(hide yes)
			(effects
				(font
					(size 1.27 1.27)
				)
			)
		)
		(property "Value" "SCD01U50V2KX-1GP"
			(at 1.1811 -2.7051 90)
			(unlocked yes)
			(layer "F.Fab")
			(hide yes)
			(effects
				(font
					(size 1.016 1.016)
					(thickness 0.1524)
				)
			)
		)
		(property "Device Type" "C402H22"
			(at 1.1811 -4.2291 90)
			(unlocked yes)
			(layer "F.Fab")
			(hide yes)
			(effects
				(font
					(size 1.016 1.016)
					(thickness 0.1524)
				)
			)
		)
		(duplicate_pad_numbers_are_jumpers no)
		(fp_rect
			(start -0.4318 0.9525)
			(end 0.4318 -0.9525)
			(stroke
				(width 0)
				(type default)
			)
			(fill no)
			(layer "F.CrtYd")
		)
		(fp_rect
			(start -0.4318 0.9525)
			(end 0.4318 -0.9525)
			(stroke
				(width 0)
				(type default)
			)
			(fill no)
			(layer "F.Fab")
		)
		(pad "1" smd custom
			(at 0 -0.4445 90)
			(size 0.1524 0.1524)
			(layers "F.Cu" "F.Mask" "F.Paste")
			(net "HDD_PRSNT_15")
			(options
				(clearance outline)
				(anchor circle)
			)
			(primitives
				(gr_poly
					(pts
						(arc
							(start 0.3048 -0.2032)
							(mid 0.275042 -0.275042)
							(end 0.2032 -0.3048)
						)
						(arc
							(start -0.2032 -0.3048)
							(mid -0.275042 -0.275042)
							(end -0.3048 -0.2032)
						)
						(arc
							(start -0.3048 0.2032)
							(mid -0.275042 0.275042)
							(end -0.2032 0.3048)
						)
						(arc
							(start 0.2032 0.3048)
							(mid 0.275042 0.275042)
							(end 0.3048 0.2032)
						)
					)
					(width 0)
					(fill yes)
				)
			)
		)
		(pad "2" smd custom
			(at 0 0.4445 90)
			(size 0.1524 0.1524)
			(layers "F.Cu" "F.Mask" "F.Paste")
			(net "GND")
			(options
				(clearance outline)
				(anchor circle)
			)
			(primitives
				(gr_poly
					(pts
						(arc
							(start 0.3048 -0.2032)
							(mid 0.275042 -0.275042)
							(end 0.2032 -0.3048)
						)
						(arc
							(start -0.2032 -0.3048)
							(mid -0.275042 -0.275042)
							(end -0.3048 -0.2032)
						)
						(arc
							(start -0.3048 0.2032)
							(mid -0.275042 0.275042)
							(end -0.2032 0.3048)
						)
						(arc
							(start 0.2032 0.3048)
							(mid 0.275042 0.275042)
							(end 0.3048 0.2032)
						)
					)
					(width 0)
					(fill yes)
				)
			)
		)
	)
	(footprint ""
		(layer "F.Cu")
		(at 172.466 -64.683894 -90)
		(property "Reference" "C422"
			(at 0 0 270)
			(layer "F.SilkS")
			(hide yes)
			(effects
				(font
					(size 1.27 1.27)
				)
			)
		)
		(property "Value" "SC4D7U25V5KX-1-GP"
			(at -0.0762 -6.1214 270)
			(unlocked yes)
			(layer "F.Fab")
			(hide yes)
			(effects
				(font
					(size 1.016 1.016)
					(thickness 0.1524)
				)
			)
		)
		(property "Device Type" "C805H58"
			(at -0.0762 -8.1534 270)
			(unlocked yes)
			(layer "F.Fab")
			(hide yes)
			(effects
				(font
					(size 1.016 1.016)
					(thickness 0.1524)
				)
			)
		)
		(duplicate_pad_numbers_are_jumpers no)
		(fp_line
			(start 0.635 0)
			(end -0.635 0)
			(stroke
				(width 0.508)
				(type default)
			)
			(layer "F.SilkS")
		)
		(fp_rect
			(start -0.9652 1.778)
			(end 0.9652 -1.778)
			(stroke
				(width 0)
				(type default)
			)
			(fill no)
			(layer "F.CrtYd")
		)
		(fp_poly
			(pts
				(xy -0.9652 -1.778) (xy 0.9652 -1.778) (xy 0.9652 1.778) (xy -0.9652 1.778)
			)
			(stroke
				(width 0)
				(type default)
			)
			(fill no)
			(layer "F.Fab")
		)
		(pad "1" smd rect
			(at 0 -0.9652 270)
			(size 1.397 1.143)
			(layers "F.Cu" "F.Mask" "F.Paste")
			(net "P12V_HDD29")
		)
		(pad "2" smd rect
			(at 0 0.9652 270)
			(size 1.397 1.143)
			(layers "F.Cu" "F.Mask" "F.Paste")
			(net "GND")
		)
	)
	(footprint ""
		(layer "F.Cu")
		(at 312.595768 -57.18175 -90)
		(property "Reference" "C82"
			(at 0 0 270)
			(layer "F.SilkS")
			(hide yes)
			(effects
				(font
					(size 1.27 1.27)
				)
			)
		)
		(property "Value" "SCD1U16V2KX-3GP"
			(at 1.1811 -2.7051 270)
			(unlocked yes)
			(layer "F.Fab")
			(hide yes)
			(effects
				(font
					(size 1.016 1.016)
					(thickness 0.1524)
				)
			)
		)
		(property "Device Type" "C402H22"
			(at 1.1811 -4.2291 270)
			(unlocked yes)
			(layer "F.Fab")
			(hide yes)
			(effects
				(font
					(size 1.016 1.016)
					(thickness 0.1524)
				)
			)
		)
		(duplicate_pad_numbers_are_jumpers no)
		(fp_rect
			(start -0.4318 0.9525)
			(end 0.4318 -0.9525)
			(stroke
				(width 0)
				(type default)
			)
			(fill no)
			(layer "F.CrtYd")
		)
		(fp_rect
			(start -0.4318 0.9525)
			(end 0.4318 -0.9525)
			(stroke
				(width 0)
				(type default)
			)
			(fill no)
			(layer "F.Fab")
		)
		(pad "1" smd custom
			(at 0 -0.4445 270)
			(size 0.1524 0.1524)
			(layers "F.Cu" "F.Mask" "F.Paste")
			(net "P3V3_STBY_B")
			(options
				(clearance outline)
				(anchor circle)
			)
			(primitives
				(gr_poly
					(pts
						(arc
							(start 0.3048 -0.2032)
							(mid 0.275042 -0.275042)
							(end 0.2032 -0.3048)
						)
						(arc
							(start -0.2032 -0.3048)
							(mid -0.275042 -0.275042)
							(end -0.3048 -0.2032)
						)
						(arc
							(start -0.3048 0.2032)
							(mid -0.275042 0.275042)
							(end -0.2032 0.3048)
						)
						(arc
							(start 0.2032 0.3048)
							(mid 0.275042 0.275042)
							(end 0.3048 0.2032)
						)
					)
					(width 0)
					(fill yes)
				)
			)
		)
		(pad "2" smd custom
			(at 0 0.4445 270)
			(size 0.1524 0.1524)
			(layers "F.Cu" "F.Mask" "F.Paste")
			(net "GND")
			(options
				(clearance outline)
				(anchor circle)
			)
			(primitives
				(gr_poly
					(pts
						(arc
							(start 0.3048 -0.2032)
							(mid 0.275042 -0.275042)
							(end 0.2032 -0.3048)
						)
						(arc
							(start -0.2032 -0.3048)
							(mid -0.275042 -0.275042)
							(end -0.3048 -0.2032)
						)
						(arc
							(start -0.3048 0.2032)
							(mid -0.275042 0.275042)
							(end -0.2032 0.3048)
						)
						(arc
							(start 0.2032 0.3048)
							(mid 0.275042 0.275042)
							(end 0.3048 0.2032)
						)
					)
					(width 0)
					(fill yes)
				)
			)
		)
	)
	(footprint ""
		(layer "F.Cu")
		(at 111.524796 -161.649918 180)
		(property "Reference" "D15"
			(at 0 0 180)
			(layer "F.SilkS")
			(hide yes)
			(effects
				(font
					(size 1.27 1.27)
				)
			)
		)
		(property "Value" "RB551V30-GP"
			(at 0 -6.7818 180)
			(unlocked yes)
			(layer "F.Fab")
			(hide yes)
			(effects
				(font
					(size 1.016 1.016)
					(thickness 0.1524)
				)
			)
		)
		(property "Device Type" "SOD323AKH38"
			(at 0 -8.6868 180)
			(unlocked yes)
			(layer "F.Fab")
			(hide yes)
			(effects
				(font
					(size 1.016 1.016)
					(thickness 0.1524)
				)
			)
		)
		(duplicate_pad_numbers_are_jumpers no)
		(fp_line
			(start 0.889 2.159)
			(end -0.889 2.159)
			(stroke
				(width 0.1524)
				(type default)
			)
			(layer "F.SilkS")
		)
		(fp_line
			(start 0.889 -1.9304)
			(end 0.889 2.159)
			(stroke
				(width 0.1524)
				(type default)
			)
			(layer "F.SilkS")
		)
		(fp_line
			(start 0.762 2.0574)
			(end -0.762 2.0574)
			(stroke
				(width 0.508)
				(type default)
			)
			(layer "F.SilkS")
		)
		(fp_line
			(start -0.889 2.159)
			(end -0.889 -1.9304)
			(stroke
				(width 0.1524)
				(type default)
			)
			(layer "F.SilkS")
		)
		(fp_line
			(start -0.889 -1.9304)
			(end 0.889 -1.9304)
			(stroke
				(width 0.1524)
				(type default)
			)
			(layer "F.SilkS")
		)
		(fp_rect
			(start -1.016 2.3114)
			(end 1.016 -2.0066)
			(stroke
				(width 0)
				(type default)
			)
			(fill no)
			(layer "F.CrtYd")
		)
		(fp_poly
			(pts
				(xy -1.016 -2.0066) (xy 1.016 -2.0066) (xy 1.016 2.3114) (xy -1.016 2.3114)
			)
			(stroke
				(width 0)
				(type default)
			)
			(fill no)
			(layer "F.Fab")
		)
		(pad "A" smd rect
			(at 0 -1.143 180)
			(size 0.5588 1.016)
			(layers "F.Cu" "F.Mask" "F.Paste")
			(net "SW_HDD_R15")
		)
		(pad "K" smd rect
			(at 0 1.143 180)
			(size 0.5588 1.016)
			(layers "F.Cu" "F.Mask" "F.Paste")
			(net "SW_HDD_N15")
		)
	)
)
